(kicad_pcb
	(version 20260206)
	(generator "pcbnew")
	(generator_version "10.0")
	(general
		(thickness 1.6)
		(legacy_teardrops no)
	)
	(paper "A4")
	(title_block
		(title "Wiwynn_Tioga_Pass_MB.brd")
		(comment 1 "Tioga Pass / footprints 2912-2918 of 4770")
	)
	(layers
		(0 "F.Cu" signal "TOP")
		(4 "In1.Cu" signal "L2GND")
		(6 "In2.Cu" signal "L3")
		(8 "In3.Cu" signal "L4GND")
		(10 "In4.Cu" signal "L5")
		(12 "In5.Cu" signal "L6GND")
		(14 "In6.Cu" signal "L7VCC")
		(16 "In7.Cu" signal "L8VCC")
		(18 "In8.Cu" signal "L9GND")
		(20 "In9.Cu" signal "L10")
		(22 "In10.Cu" signal "L11GND")
		(24 "In11.Cu" signal "L12")
		(26 "In12.Cu" signal "L13GND")
		(2 "B.Cu" signal "BOTTOM")
		(9 "F.Adhes" user "F.Adhesive")
		(11 "B.Adhes" user "B.Adhesive")
		(13 "F.Paste" user "Package Geometry/Pastemask Top")
		(15 "B.Paste" user "Package Geometry/Pastemask Bottom")
		(5 "F.SilkS" user "Ref Des/Silkscreen Top")
		(7 "B.SilkS" user "Ref Des/Silkscreen Bottom")
		(1 "F.Mask" user "Board Geometry/Soldermask Top")
		(3 "B.Mask" user "Board Geometry/Soldermask Bottom")
		(17 "Dwgs.User" user "User.Drawings")
		(19 "Cmts.User" user "User.Comments")
		(21 "Eco1.User" user "User.Eco1")
		(23 "Eco2.User" user "User.Eco2")
		(25 "Edge.Cuts" user "Board Geometry/Outline")
		(27 "Margin" user)
		(31 "F.CrtYd" user "Package Geometry/Place Bound Top")
		(29 "B.CrtYd" user "Package Geometry/Place Bound Bottom")
		(35 "F.Fab" user "Ref Des/Assembly Top")
		(33 "B.Fab" user "Ref Des/Assembly Bottom")
	)
	(footprint ""
		(layer "B.Cu")
		(at 404.3172 -30.861 90)
		(property "Reference" "R25W115"
			(at 0.8382 -0.67818 90)
			(unlocked yes)
			(layer "B.SilkS")
			(effects
				(font
					(size 0.4064 0.254)
					(thickness 0.1524)
				)
				(justify left mirror)
			)
		)
		(property "Value" ""
			(at 0 0 90)
			(layer "B.Fab")
			(effects
				(font
					(size 1.27 1.27)
				)
				(justify mirror)
			)
		)
		(duplicate_pad_numbers_are_jumpers no)
		(fp_poly
			(pts
				(xy 0.2794 -0.1016) (xy -0.2794 -0.1016) (xy -0.2794 0.9906) (xy 0.2794 0.9906)
			)
			(stroke
				(width 0)
				(type default)
			)
			(fill no)
			(layer "B.CrtYd")
		)
		(fp_line
			(start 0.2794 -0.1016)
			(end 0.2794 0.9906)
			(stroke
				(width 0.1)
				(type default)
			)
			(layer "B.Fab")
		)
		(fp_line
			(start -0.2794 -0.1016)
			(end 0.2794 -0.1016)
			(stroke
				(width 0.1)
				(type default)
			)
			(layer "B.Fab")
		)
		(fp_line
			(start 0.2794 0.9906)
			(end -0.2794 0.9906)
			(stroke
				(width 0.1)
				(type default)
			)
			(layer "B.Fab")
		)
		(fp_line
			(start -0.2794 0.9906)
			(end -0.2794 -0.1016)
			(stroke
				(width 0.1)
				(type default)
			)
			(layer "B.Fab")
		)
		(pad "1" smd rect
			(at 0 0 270)
			(size 0.508 0.508)
			(layers "B.Cu" "B.Mask" "B.Paste")
			(net "P3V3_STBY")
		)
		(pad "2" smd rect
			(at 0 0.889 270)
			(size 0.508 0.508)
			(layers "B.Cu" "B.Mask" "B.Paste")
			(net "TP_RGMII1TXD3_GPIOT5")
		)
		(zone
			(layer "B.Cu")
			(hatch none 0.5)
			(connect_pads
				(clearance 0)
			)
			(min_thickness 0.25)
			(keepout
				(tracks allowed)
				(vias not_allowed)
				(pads allowed)
				(copperpour not_allowed)
				(footprints allowed)
			)
			(placement
				(enabled no)
				(sheetname "")
			)
			(fill
				(thermal_gap 0.5)
				(thermal_bridge_width 0.5)
				(island_removal_mode 0)
			)
			(polygon
				(pts
					(xy 404.5712 -31.115) (xy 404.5712 -30.607) (xy 404.9522 -30.607) (xy 404.9522 -31.115)
				)
			)
		)
		(zone
			(layer "B.Cu")
			(hatch none 0.5)
			(connect_pads
				(clearance 0)
			)
			(min_thickness 0.25)
			(keepout
				(tracks not_allowed)
				(vias allowed)
				(pads allowed)
				(copperpour not_allowed)
				(footprints allowed)
			)
			(placement
				(enabled no)
				(sheetname "")
			)
			(fill
				(thermal_gap 0.5)
				(thermal_bridge_width 0.5)
				(island_removal_mode 0)
			)
			(polygon
				(pts
					(xy 404.9522 -31.115) (xy 404.9522 -30.607) (xy 404.5712 -30.607) (xy 404.5712 -31.115)
				)
			)
		)
	)
	(footprint ""
		(layer "B.Cu")
		(at 463.15122 -13.215366 -90)
		(property "Reference" "R2T4"
			(at 0 0 90)
			(layer "B.SilkS")
			(hide yes)
			(effects
				(font
					(size 1.27 1.27)
				)
				(justify mirror)
			)
		)
		(property "Value" ""
			(at 0 0 90)
			(layer "B.Fab")
			(effects
				(font
					(size 1.27 1.27)
				)
				(justify mirror)
			)
		)
		(duplicate_pad_numbers_are_jumpers no)
		(fp_rect
			(start 0.2794 -0.1016)
			(end -0.2794 0.9906)
			(stroke
				(width 0)
				(type default)
			)
			(fill no)
			(layer "B.CrtYd")
		)
		(fp_line
			(start -0.2794 0.9906)
			(end -0.2794 -0.1016)
			(stroke
				(width 0.1)
				(type default)
			)
			(layer "B.Fab")
		)
		(fp_line
			(start 0.2794 0.9906)
			(end -0.2794 0.9906)
			(stroke
				(width 0.1)
				(type default)
			)
			(layer "B.Fab")
		)
		(fp_line
			(start -0.2794 -0.1016)
			(end 0.2794 -0.1016)
			(stroke
				(width 0.1)
				(type default)
			)
			(layer "B.Fab")
		)
		(fp_line
			(start 0.2794 -0.1016)
			(end 0.2794 0.9906)
			(stroke
				(width 0.1)
				(type default)
			)
			(layer "B.Fab")
		)
		(pad "1" smd rect
			(at 0 0 90)
			(size 0.508 0.508)
			(layers "B.Cu" "B.Mask" "B.Paste")
			(net "P3V3_STBY")
		)
		(pad "2" smd rect
			(at 0 0.889 90)
			(size 0.508 0.508)
			(layers "B.Cu" "B.Mask" "B.Paste")
			(net "GND")
		)
		(zone
			(layer "B.Cu")
			(hatch none 0.5)
			(connect_pads
				(clearance 0)
			)
			(min_thickness 0.25)
			(keepout
				(tracks allowed)
				(vias not_allowed)
				(pads allowed)
				(copperpour not_allowed)
				(footprints allowed)
			)
			(placement
				(enabled no)
				(sheetname "")
			)
			(fill
				(thermal_gap 0.5)
				(thermal_bridge_width 0.5)
				(island_removal_mode 0)
			)
			(polygon
				(pts
					(xy 462.89722 -12.961366) (xy 462.89722 -13.469366) (xy 462.51622 -13.469366) (xy 462.51622 -12.961366)
				)
			)
		)
		(zone
			(layer "B.Cu")
			(hatch none 0.5)
			(connect_pads
				(clearance 0)
			)
			(min_thickness 0.25)
			(keepout
				(tracks not_allowed)
				(vias allowed)
				(pads allowed)
				(copperpour not_allowed)
				(footprints allowed)
			)
			(placement
				(enabled no)
				(sheetname "")
			)
			(fill
				(thermal_gap 0.5)
				(thermal_bridge_width 0.5)
				(island_removal_mode 0)
			)
			(polygon
				(pts
					(xy 462.89722 -12.961366) (xy 462.89722 -13.469366) (xy 462.51622 -13.469366) (xy 462.51622 -12.961366)
				)
			)
		)
	)
	(footprint ""
		(layer "B.Cu")
		(at 402.881846 -24.838152)
		(property "Reference" "C9G21"
			(at 0 0 0)
			(layer "B.SilkS")
			(hide yes)
			(effects
				(font
					(size 1.27 1.27)
				)
				(justify mirror)
			)
		)
		(property "Value" ""
			(at 0 0 0)
			(layer "B.Fab")
			(effects
				(font
					(size 1.27 1.27)
				)
				(justify mirror)
			)
		)
		(duplicate_pad_numbers_are_jumpers no)
		(fp_poly
			(pts
				(xy -0.3048 -0.1016) (xy -0.3048 0.9906) (xy 0.3048 0.9906) (xy 0.3048 -0.1016)
			)
			(stroke
				(width 0)
				(type default)
			)
			(fill no)
			(layer "B.CrtYd")
		)
		(fp_line
			(start -0.3048 -0.1016)
			(end 0.3048 -0.1016)
			(stroke
				(width 0.1)
				(type default)
			)
			(layer "B.Fab")
		)
		(fp_line
			(start -0.3048 0.9906)
			(end -0.3048 -0.1016)
			(stroke
				(width 0.1)
				(type default)
			)
			(layer "B.Fab")
		)
		(fp_line
			(start 0.3048 -0.1016)
			(end 0.3048 0.9906)
			(stroke
				(width 0.1)
				(type default)
			)
			(layer "B.Fab")
		)
		(fp_line
			(start 0.3048 0.9906)
			(end -0.3048 0.9906)
			(stroke
				(width 0.1)
				(type default)
			)
			(layer "B.Fab")
		)
		(pad "1" smd rect
			(at 0 0 180)
			(size 0.508 0.508)
			(layers "B.Cu" "B.Mask" "B.Paste")
			(net "A_P5V_STBY_SCALED")
		)
		(pad "2" smd rect
			(at 0 0.889 180)
			(size 0.508 0.508)
			(layers "B.Cu" "B.Mask" "B.Paste")
			(net "GND")
		)
		(zone
			(layer "B.Cu")
			(hatch none 0.5)
			(connect_pads
				(clearance 0)
			)
			(min_thickness 0.25)
			(keepout
				(tracks allowed)
				(vias not_allowed)
				(pads allowed)
				(copperpour not_allowed)
				(footprints allowed)
			)
			(placement
				(enabled no)
				(sheetname "")
			)
			(fill
				(thermal_gap 0.5)
				(thermal_bridge_width 0.5)
				(island_removal_mode 0)
			)
			(polygon
				(pts
					(xy 403.135846 -24.584152) (xy 402.627846 -24.584152) (xy 402.627846 -24.203152) (xy 403.135846 -24.203152)
				)
			)
		)
		(zone
			(layer "B.Cu")
			(hatch none 0.5)
			(connect_pads
				(clearance 0)
			)
			(min_thickness 0.25)
			(keepout
				(tracks not_allowed)
				(vias allowed)
				(pads allowed)
				(copperpour not_allowed)
				(footprints allowed)
			)
			(placement
				(enabled no)
				(sheetname "")
			)
			(fill
				(thermal_gap 0.5)
				(thermal_bridge_width 0.5)
				(island_removal_mode 0)
			)
			(polygon
				(pts
					(xy 403.135846 -24.203152) (xy 402.627846 -24.203152) (xy 402.627846 -24.584152) (xy 403.135846 -24.584152)
				)
			)
		)
	)
	(footprint ""
		(layer "B.Cu")
		(at 252.1585 -8.1534 -90)
		(property "Reference" "C5U7"
			(at -1.848866 0.752348 270)
			(unlocked yes)
			(layer "B.SilkS")
			(effects
				(font
					(size 1.27 0.9652)
					(thickness 0.1524)
				)
				(justify mirror)
			)
		)
		(property "Value" ""
			(at 0 0 90)
			(layer "B.Fab")
			(effects
				(font
					(size 1.27 1.27)
				)
				(justify mirror)
			)
		)
		(duplicate_pad_numbers_are_jumpers no)
		(fp_rect
			(start 0.500126 1.598422)
			(end -0.500126 -0.201422)
			(stroke
				(width 0)
				(type default)
			)
			(fill no)
			(layer "B.CrtYd")
		)
		(fp_line
			(start -0.500126 1.598422)
			(end 0.500126 1.598422)
			(stroke
				(width 0.1)
				(type default)
			)
			(layer "B.Fab")
		)
		(fp_line
			(start 0.500126 1.598422)
			(end 0.500126 -0.201422)
			(stroke
				(width 0.1)
				(type default)
			)
			(layer "B.Fab")
		)
		(fp_line
			(start -0.500126 -0.201422)
			(end -0.500126 1.598422)
			(stroke
				(width 0.1)
				(type default)
			)
			(layer "B.Fab")
		)
		(fp_line
			(start 0.500126 -0.201422)
			(end -0.500126 -0.201422)
			(stroke
				(width 0.1)
				(type default)
			)
			(layer "B.Fab")
		)
		(pad "1" smd rect
			(at 0 0 180)
			(size 0.889 0.9906)
			(layers "B.Cu" "B.Mask" "B.Paste")
			(net "PVDDQ_ABC")
		)
		(pad "2" smd rect
			(at 0 1.397 180)
			(size 0.889 0.9906)
			(layers "B.Cu" "B.Mask" "B.Paste")
			(net "GND")
		)
		(zone
			(layer "B.Cu")
			(hatch none 0.5)
			(connect_pads
				(clearance 0)
			)
			(min_thickness 0.25)
			(keepout
				(tracks not_allowed)
				(vias allowed)
				(pads allowed)
				(copperpour not_allowed)
				(footprints allowed)
			)
			(placement
				(enabled no)
				(sheetname "")
			)
			(fill
				(thermal_gap 0.5)
				(thermal_bridge_width 0.5)
				(island_removal_mode 0)
			)
			(polygon
				(pts
					(xy 251.206 -7.6581) (xy 251.714 -7.6581) (xy 251.714 -8.6487) (xy 251.206 -8.6487)
				)
			)
		)
		(zone
			(layer "B.Cu")
			(hatch none 0.5)
			(connect_pads
				(clearance 0)
			)
			(min_thickness 0.25)
			(keepout
				(tracks allowed)
				(vias not_allowed)
				(pads allowed)
				(copperpour not_allowed)
				(footprints allowed)
			)
			(placement
				(enabled no)
				(sheetname "")
			)
			(fill
				(thermal_gap 0.5)
				(thermal_bridge_width 0.5)
				(island_removal_mode 0)
			)
			(polygon
				(pts
					(xy 251.206 -7.6581) (xy 251.714 -7.6581) (xy 251.714 -8.6487) (xy 251.206 -8.6487)
				)
			)
		)
	)
	(footprint ""
		(layer "B.Cu")
		(at 354.289614 -126.624842 -90)
		(property "Reference" "R767"
			(at 0.8382 -0.67818 270)
			(unlocked yes)
			(layer "B.SilkS")
			(effects
				(font
					(size 0.4064 0.254)
					(thickness 0.1524)
				)
				(justify left mirror)
			)
		)
		(property "Value" ""
			(at 0 0 90)
			(layer "B.Fab")
			(effects
				(font
					(size 1.27 1.27)
				)
				(justify mirror)
			)
		)
		(duplicate_pad_numbers_are_jumpers no)
		(fp_poly
			(pts
				(xy 0.2794 -0.1016) (xy -0.2794 -0.1016) (xy -0.2794 0.9906) (xy 0.2794 0.9906)
			)
			(stroke
				(width 0)
				(type default)
			)
			(fill no)
			(layer "B.CrtYd")
		)
		(fp_line
			(start -0.2794 0.9906)
			(end -0.2794 -0.1016)
			(stroke
				(width 0.1)
				(type default)
			)
			(layer "B.Fab")
		)
		(fp_line
			(start 0.2794 0.9906)
			(end -0.2794 0.9906)
			(stroke
				(width 0.1)
				(type default)
			)
			(layer "B.Fab")
		)
		(fp_line
			(start -0.2794 -0.1016)
			(end 0.2794 -0.1016)
			(stroke
				(width 0.1)
				(type default)
			)
			(layer "B.Fab")
		)
		(fp_line
			(start 0.2794 -0.1016)
			(end 0.2794 0.9906)
			(stroke
				(width 0.1)
				(type default)
			)
			(layer "B.Fab")
		)
		(pad "1" smd rect
			(at 0 0 90)
			(size 0.508 0.508)
			(layers "B.Cu" "B.Mask" "B.Paste")
			(net "P3E_CPU0_PE1_PCH_RXP<15>")
		)
		(pad "2" smd rect
			(at 0 0.889 90)
			(size 0.508 0.508)
			(layers "B.Cu" "B.Mask" "B.Paste")
			(net "P3E_CPU0_PE1_PCH_CON_RXP<15>")
		)
		(zone
			(layer "B.Cu")
			(hatch none 0.5)
			(connect_pads
				(clearance 0)
			)
			(min_thickness 0.25)
			(keepout
				(tracks not_allowed)
				(vias allowed)
				(pads allowed)
				(copperpour not_allowed)
				(footprints allowed)
			)
			(placement
				(enabled no)
				(sheetname "")
			)
			(fill
				(thermal_gap 0.5)
				(thermal_bridge_width 0.5)
				(island_removal_mode 0)
			)
			(polygon
				(pts
					(xy 353.654614 -126.370842) (xy 353.654614 -126.878842) (xy 354.035614 -126.878842) (xy 354.035614 -126.370842)
				)
			)
		)
		(zone
			(layer "B.Cu")
			(hatch none 0.5)
			(connect_pads
				(clearance 0)
			)
			(min_thickness 0.25)
			(keepout
				(tracks allowed)
				(vias not_allowed)
				(pads allowed)
				(copperpour not_allowed)
				(footprints allowed)
			)
			(placement
				(enabled no)
				(sheetname "")
			)
			(fill
				(thermal_gap 0.5)
				(thermal_bridge_width 0.5)
				(island_removal_mode 0)
			)
			(polygon
				(pts
					(xy 354.035614 -126.370842) (xy 354.035614 -126.878842) (xy 353.654614 -126.878842) (xy 353.654614 -126.370842)
				)
			)
		)
	)
	(footprint ""
		(layer "B.Cu")
		(at 446.8876 -62.5856 -90)
		(property "Reference" "R1W43"
			(at 0.8382 -0.67818 270)
			(unlocked yes)
			(layer "B.SilkS")
			(effects
				(font
					(size 0.4064 0.254)
					(thickness 0.1524)
				)
				(justify left mirror)
			)
		)
		(property "Value" ""
			(at 0 0 90)
			(layer "B.Fab")
			(effects
				(font
					(size 1.27 1.27)
				)
				(justify mirror)
			)
		)
		(duplicate_pad_numbers_are_jumpers no)
		(fp_poly
			(pts
				(xy 0.2794 -0.1016) (xy -0.2794 -0.1016) (xy -0.2794 0.9906) (xy 0.2794 0.9906)
			)
			(stroke
				(width 0)
				(type default)
			)
			(fill no)
			(layer "B.CrtYd")
		)
		(fp_line
			(start -0.2794 0.9906)
			(end -0.2794 -0.1016)
			(stroke
				(width 0.1)
				(type default)
			)
			(layer "B.Fab")
		)
		(fp_line
			(start 0.2794 0.9906)
			(end -0.2794 0.9906)
			(stroke
				(width 0.1)
				(type default)
			)
			(layer "B.Fab")
		)
		(fp_line
			(start -0.2794 -0.1016)
			(end 0.2794 -0.1016)
			(stroke
				(width 0.1)
				(type default)
			)
			(layer "B.Fab")
		)
		(fp_line
			(start 0.2794 -0.1016)
			(end 0.2794 0.9906)
			(stroke
				(width 0.1)
				(type default)
			)
			(layer "B.Fab")
		)
		(pad "1" smd rect
			(at 0 0 90)
			(size 0.508 0.508)
			(layers "B.Cu" "B.Mask" "B.Paste")
			(net "P3V3_STBY")
		)
		(pad "2" smd rect
			(at 0 0.889 90)
			(size 0.508 0.508)
			(layers "B.Cu" "B.Mask" "B.Paste")
			(net "FM_GBE1_LVC3_MOD_ABS")
		)
		(zone
			(layer "B.Cu")
			(hatch none 0.5)
			(connect_pads
				(clearance 0)
			)
			(min_thickness 0.25)
			(keepout
				(tracks not_allowed)
				(vias allowed)
				(pads allowed)
				(copperpour not_allowed)
				(footprints allowed)
			)
			(placement
				(enabled no)
				(sheetname "")
			)
			(fill
				(thermal_gap 0.5)
				(thermal_bridge_width 0.5)
				(island_removal_mode 0)
			)
			(polygon
				(pts
					(xy 446.2526 -62.3316) (xy 446.2526 -62.8396) (xy 446.6336 -62.8396) (xy 446.6336 -62.3316)
				)
			)
		)
		(zone
			(layer "B.Cu")
			(hatch none 0.5)
			(connect_pads
				(clearance 0)
			)
			(min_thickness 0.25)
			(keepout
				(tracks allowed)
				(vias not_allowed)
				(pads allowed)
				(copperpour not_allowed)
				(footprints allowed)
			)
			(placement
				(enabled no)
				(sheetname "")
			)
			(fill
				(thermal_gap 0.5)
				(thermal_bridge_width 0.5)
				(island_removal_mode 0)
			)
			(polygon
				(pts
					(xy 446.6336 -62.3316) (xy 446.6336 -62.8396) (xy 446.2526 -62.8396) (xy 446.2526 -62.3316)
				)
			)
		)
	)
	(footprint ""
		(layer "B.Cu")
		(at 129.786888 -64.934338 -90)
		(property "Reference" "R7P29"
			(at 0 0 90)
			(layer "B.SilkS")
			(hide yes)
			(effects
				(font
					(size 1.27 1.27)
				)
				(justify mirror)
			)
		)
		(property "Value" ""
			(at 0 0 90)
			(layer "B.Fab")
			(effects
				(font
					(size 1.27 1.27)
				)
				(justify mirror)
			)
		)
		(duplicate_pad_numbers_are_jumpers no)
		(fp_rect
			(start -0.2794 0.9906)
			(end 0.2794 -0.1016)
			(stroke
				(width 0)
				(type default)
			)
			(fill no)
			(layer "B.CrtYd")
		)
		(fp_line
			(start -0.2794 0.9906)
			(end -0.2794 -0.1016)
			(stroke
				(width 0.1)
				(type default)
			)
			(layer "B.Fab")
		)
		(fp_line
			(start 0.2794 0.9906)
			(end -0.2794 0.9906)
			(stroke
				(width 0.1)
				(type default)
			)
			(layer "B.Fab")
		)
		(fp_line
			(start -0.2794 -0.1016)
			(end 0.2794 -0.1016)
			(stroke
				(width 0.1)
				(type default)
			)
			(layer "B.Fab")
		)
		(fp_line
			(start 0.2794 -0.1016)
			(end 0.2794 0.9906)
			(stroke
				(width 0.1)
				(type default)
			)
			(layer "B.Fab")
		)
		(pad "1" smd rect
			(at 0 0 90)
			(size 0.508 0.508)
			(layers "B.Cu" "B.Mask" "B.Paste")
			(net "XDP_CPU_TCK0")
		)
		(pad "2" smd rect
			(at 0 0.889 90)
			(size 0.508 0.508)
			(layers "B.Cu" "B.Mask" "B.Paste")
			(net "GND")
		)
		(zone
			(layer "B.Cu")
			(hatch none 0.5)
			(connect_pads
				(clearance 0)
			)
			(min_thickness 0.25)
			(keepout
				(tracks allowed)
				(vias not_allowed)
				(pads allowed)
				(copperpour not_allowed)
				(footprints allowed)
			)
			(placement
				(enabled no)
				(sheetname "")
			)
			(fill
				(thermal_gap 0.5)
				(thermal_bridge_width 0.5)
				(island_removal_mode 0)
			)
			(polygon
				(pts
					(xy 129.151888 -65.188338) (xy 129.151888 -64.680338) (xy 129.532888 -64.680338) (xy 129.532888 -65.188338)
				)
			)
		)
		(zone
			(layer "B.Cu")
			(hatch none 0.5)
			(connect_pads
				(clearance 0)
			)
			(min_thickness 0.25)
			(keepout
				(tracks not_allowed)
				(vias allowed)
				(pads allowed)
				(copperpour not_allowed)
				(footprints allowed)
			)
			(placement
				(enabled no)
				(sheetname "")
			)
			(fill
				(thermal_gap 0.5)
				(thermal_bridge_width 0.5)
				(island_removal_mode 0)
			)
			(polygon
				(pts
					(xy 129.151888 -65.188338) (xy 129.151888 -64.680338) (xy 129.532888 -64.680338) (xy 129.532888 -65.188338)
				)
			)
		)
	)
)
